(kicad_pcb
	(version 20241229)
	(generator "pcbnew")
	(generator_version "9.0")
	(general
		(thickness 1.61)
		(legacy_teardrops no)
	)
	(paper "A3")
	(title_block
		(title "RDIMM DDR5 Tester")
		(date "2026-05-21")
		(rev "2.2.0")
		(company "Antmicro")
		(comment 9 "footprints 97-101 of 796")
	)
	(layers
		(0 "F.Cu" signal)
		(4 "In1.Cu" power)
		(6 "In2.Cu" mixed)
		(8 "In3.Cu" power)
		(10 "In4.Cu" mixed)
		(12 "In5.Cu" power)
		(14 "In6.Cu" mixed)
		(16 "In7.Cu" power)
		(18 "In8.Cu" power)
		(20 "In9.Cu" mixed)
		(22 "In10.Cu" power)
		(2 "B.Cu" signal)
		(9 "F.Adhes" user "F.Adhesive")
		(11 "B.Adhes" user "B.Adhesive")
		(13 "F.Paste" user)
		(15 "B.Paste" user)
		(5 "F.SilkS" user "F.Silkscreen")
		(7 "B.SilkS" user "B.Silkscreen")
		(1 "F.Mask" user)
		(3 "B.Mask" user)
		(17 "Dwgs.User" user "User.Drawings")
		(19 "Cmts.User" user "User.Comments")
		(21 "Eco1.User" user "User.Eco1")
		(23 "Eco2.User" user "User.Eco2")
		(25 "Edge.Cuts" user)
		(27 "Margin" user)
		(31 "F.CrtYd" user "F.Courtyard")
		(29 "B.CrtYd" user "B.Courtyard")
		(35 "F.Fab" user)
		(33 "B.Fab" user)
	)
	(footprint "antmicro-footprints:C_0402_1005Metric"
		(layer "F.Cu")
		(at 123.766 187.222 -90)
		(descr "Capacitor SMD 0402")
		(tags "capacitor SMD 0402")
		(property "Reference" "C294"
			(at -1.425 0.575 90)
			(layer "F.SilkS")
			(effects
				(font
					(size 0.7 0.7)
					(thickness 0.15)
				)
				(justify right bottom)
			)
		)
		(property "Value" "C_100n_0402"
			(at -1.022927 2.155213 90)
			(layer "F.Fab")
			(effects
				(font
					(size 0.7 0.7)
					(thickness 0.15)
				)
				(justify right bottom)
			)
		)
		(property "Datasheet" "https://www.murata.com/products/productdetail?partno=GRM155R61H104KE14%23"
			(at 0 0 270)
			(layer "F.Fab")
			(hide yes)
			(effects
				(font
					(size 1.27 1.27)
					(thickness 0.15)
				)
			)
		)
		(property "MPN" "GRM155R61H104KE14D"
			(at 0 0 270)
			(unlocked yes)
			(layer "F.Fab")
			(hide yes)
			(effects
				(font
					(size 1 1)
					(thickness 0.15)
				)
			)
		)
		(property "Manufacturer" "Murata"
			(at 0 0 270)
			(unlocked yes)
			(layer "F.Fab")
			(hide yes)
			(effects
				(font
					(size 1 1)
					(thickness 0.15)
				)
			)
		)
		(property "License" "Apache-2.0"
			(at 0 0 270)
			(unlocked yes)
			(layer "F.Fab")
			(hide yes)
			(effects
				(font
					(size 1 1)
					(thickness 0.15)
				)
			)
		)
		(property "Author" "Antmicro"
			(at 0 0 270)
			(unlocked yes)
			(layer "F.Fab")
			(hide yes)
			(effects
				(font
					(size 1 1)
					(thickness 0.15)
				)
			)
		)
		(property "Val" "100n"
			(at 0 0 270)
			(unlocked yes)
			(layer "F.Fab")
			(hide yes)
			(effects
				(font
					(size 1 1)
					(thickness 0.15)
				)
			)
		)
		(property "Voltage" "50V"
			(at 0 0 270)
			(unlocked yes)
			(layer "F.Fab")
			(hide yes)
			(effects
				(font
					(size 1 1)
					(thickness 0.15)
				)
			)
		)
		(property "Dielectric" "X5R"
			(at 0 0 270)
			(unlocked yes)
			(layer "F.Fab")
			(hide yes)
			(effects
				(font
					(size 1 1)
					(thickness 0.15)
				)
			)
		)
		(property "Public" ""
			(at 0 0 270)
			(unlocked yes)
			(layer "F.Fab")
			(hide yes)
			(effects
				(font
					(size 1 1)
					(thickness 0.15)
				)
			)
		)
		(sheetname "/HDMI + SD Card/")
		(sheetfile "hdmi-sd-card.kicad_sch")
		(attr smd exclude_from_bom dnp)
		(fp_rect
			(start -0.925 -0.47)
			(end 0.925 0.47)
			(stroke
				(width 0.05)
				(type default)
			)
			(fill no)
			(layer "F.CrtYd")
		)
		(fp_line
			(start -0.494 0.248)
			(end -0.494 -0.25)
			(stroke
				(width 0.15)
				(type solid)
			)
			(layer "F.Fab")
		)
		(fp_line
			(start 0.504 0.248)
			(end -0.494 0.248)
			(stroke
				(width 0.15)
				(type solid)
			)
			(layer "F.Fab")
		)
		(fp_line
			(start -0.494 -0.25)
			(end 0.504 -0.25)
			(stroke
				(width 0.15)
				(type solid)
			)
			(layer "F.Fab")
		)
		(fp_line
			(start 0.504 -0.25)
			(end 0.504 0.248)
			(stroke
				(width 0.15)
				(type solid)
			)
			(layer "F.Fab")
		)
		(fp_text user "Author: Antmicro"
			(at -0.939 3.399 270)
			(layer "F.Fab")
			(effects
				(font
					(size 0.7 0.7)
					(thickness 0.15)
				)
				(justify left bottom)
			)
		)
		(fp_text user "License: Apache-2.0"
			(at -0.939 5.799 270)
			(layer "F.Fab")
			(effects
				(font
					(size 0.7 0.7)
					(thickness 0.15)
				)
				(justify left bottom)
			)
		)
		(fp_text user "${REFERENCE}"
			(at -0.939 4.599 270)
			(layer "F.Fab")
			(effects
				(font
					(size 0.7 0.7)
					(thickness 0.15)
				)
				(justify left bottom)
			)
		)
		(pad "1" smd roundrect
			(at -0.48 0 270)
			(size 0.59 0.64)
			(layers "F.Cu" "F.Mask" "F.Paste")
			(roundrect_rratio 0.25)
			(net 385 "HDMI_OE")
			(pintype "passive")
		)
		(pad "2" smd roundrect
			(at 0.48 0 270)
			(size 0.59 0.64)
			(layers "F.Cu" "F.Mask" "F.Paste")
			(roundrect_rratio 0.25)
			(net 1 "GND")
			(pintype "passive")
		)
	)
	(footprint "antmicro-footprints:R_0402_1005Metric"
		(layer "F.Cu")
		(at 119.15 151.61 180)
		(descr "Resistor SMD 0402")
		(tags "resistor SMD 0402")
		(property "Reference" "R34"
			(at -5.11 -0.415 0)
			(layer "F.SilkS")
			(effects
				(font
					(size 0.7 0.7)
					(thickness 0.15)
				)
				(justify right bottom)
			)
		)
		(property "Value" "R_49k9_0402"
			(at -1.011843 1.772047 0)
			(layer "F.Fab")
			(effects
				(font
					(size 0.7 0.7)
					(thickness 0.15)
				)
				(justify right bottom)
			)
		)
		(property "Datasheet" "https://www.bourns.com/docs/product-datasheets/cr.pdf"
			(at 0 0 180)
			(layer "F.Fab")
			(hide yes)
			(effects
				(font
					(size 1.27 1.27)
					(thickness 0.15)
				)
			)
		)
		(property "MPN" "CR0402-FX-4992GLF"
			(at 0 0 180)
			(unlocked yes)
			(layer "F.Fab")
			(hide yes)
			(effects
				(font
					(size 1 1)
					(thickness 0.15)
				)
			)
		)
		(property "Manufacturer" "Bourns"
			(at 0 0 180)
			(unlocked yes)
			(layer "F.Fab")
			(hide yes)
			(effects
				(font
					(size 1 1)
					(thickness 0.15)
				)
			)
		)
		(property "License" "Apache-2.0"
			(at 0 0 180)
			(unlocked yes)
			(layer "F.Fab")
			(hide yes)
			(effects
				(font
					(size 1 1)
					(thickness 0.15)
				)
			)
		)
		(property "Author" "Antmicro"
			(at 0 0 180)
			(unlocked yes)
			(layer "F.Fab")
			(hide yes)
			(effects
				(font
					(size 1 1)
					(thickness 0.15)
				)
			)
		)
		(property "Val" "49k9"
			(at 0 0 180)
			(unlocked yes)
			(layer "F.Fab")
			(hide yes)
			(effects
				(font
					(size 1 1)
					(thickness 0.15)
				)
			)
		)
		(property "Tolerance" "1%"
			(at 0 0 180)
			(unlocked yes)
			(layer "F.Fab")
			(hide yes)
			(effects
				(font
					(size 1 1)
					(thickness 0.15)
				)
			)
		)
		(sheetname "/HDMI + SD Card/")
		(sheetfile "hdmi-sd-card.kicad_sch")
		(attr smd)
		(fp_rect
			(start -0.925 -0.47)
			(end 0.925 0.47)
			(stroke
				(width 0.05)
				(type default)
			)
			(fill no)
			(layer "F.CrtYd")
		)
		(fp_rect
			(start -0.5 -0.25)
			(end 0.5 0.25)
			(stroke
				(width 0.15)
				(type solid)
			)
			(fill no)
			(layer "F.Fab")
		)
		(fp_text user "License: Apache-2.0"
			(at -0.95 5.169 180)
			(layer "F.Fab")
			(effects
				(font
					(size 0.7 0.7)
					(thickness 0.15)
				)
				(justify left bottom)
			)
		)
		(fp_text user "${REFERENCE}"
			(at -0.95 3.168 180)
			(layer "F.Fab")
			(effects
				(font
					(size 0.7 0.7)
					(thickness 0.15)
				)
				(justify left bottom)
			)
		)
		(fp_text user "Author: Antmicro"
			(at -0.95 4.169 180)
			(layer "F.Fab")
			(effects
				(font
					(size 0.7 0.7)
					(thickness 0.15)
				)
				(justify left bottom)
			)
		)
		(pad "1" smd roundrect
			(at -0.48 0 180)
			(size 0.59 0.64)
			(layers "F.Cu" "F.Mask" "F.Paste")
			(roundrect_rratio 0.25)
			(net 680 "Net-(L10-Pad2)")
			(pintype "passive")
		)
		(pad "2" smd roundrect
			(at 0.48 0 180)
			(size 0.59 0.64)
			(layers "F.Cu" "F.Mask" "F.Paste")
			(roundrect_rratio 0.25)
			(net 322 "Net-(C300-Pad2)")
			(pintype "passive")
		)
	)
	(footprint "antmicro-footprints:C_0402_1005Metric"
		(layer "F.Cu")
		(at 127.711 186.1375)
		(descr "Capacitor SMD 0402")
		(tags "capacitor SMD 0402")
		(property "Reference" "C281"
			(at 1.389 0.5375 0)
			(layer "F.SilkS")
			(effects
				(font
					(size 0.7 0.7)
					(thickness 0.15)
				)
				(justify left bottom)
			)
		)
		(property "Value" "C_100n_0402"
			(at -1.022927 2.155213 0)
			(layer "F.Fab")
			(effects
				(font
					(size 0.7 0.7)
					(thickness 0.15)
				)
				(justify left bottom)
			)
		)
		(property "Datasheet" "https://www.murata.com/products/productdetail?partno=GRM155R61H104KE14%23"
			(at 0 0 0)
			(layer "F.Fab")
			(hide yes)
			(effects
				(font
					(size 1.27 1.27)
					(thickness 0.15)
				)
			)
		)
		(property "MPN" "GRM155R61H104KE14D"
			(at 0 0 0)
			(unlocked yes)
			(layer "F.Fab")
			(hide yes)
			(effects
				(font
					(size 1 1)
					(thickness 0.15)
				)
			)
		)
		(property "Manufacturer" "Murata"
			(at 0 0 0)
			(unlocked yes)
			(layer "F.Fab")
			(hide yes)
			(effects
				(font
					(size 1 1)
					(thickness 0.15)
				)
			)
		)
		(property "License" "Apache-2.0"
			(at 0 0 0)
			(unlocked yes)
			(layer "F.Fab")
			(hide yes)
			(effects
				(font
					(size 1 1)
					(thickness 0.15)
				)
			)
		)
		(property "Author" "Antmicro"
			(at 0 0 0)
			(unlocked yes)
			(layer "F.Fab")
			(hide yes)
			(effects
				(font
					(size 1 1)
					(thickness 0.15)
				)
			)
		)
		(property "Val" "100n"
			(at 0 0 0)
			(unlocked yes)
			(layer "F.Fab")
			(hide yes)
			(effects
				(font
					(size 1 1)
					(thickness 0.15)
				)
			)
		)
		(property "Voltage" "50V"
			(at 0 0 0)
			(unlocked yes)
			(layer "F.Fab")
			(hide yes)
			(effects
				(font
					(size 1 1)
					(thickness 0.15)
				)
			)
		)
		(property "Dielectric" "X5R"
			(at 0 0 0)
			(unlocked yes)
			(layer "F.Fab")
			(hide yes)
			(effects
				(font
					(size 1 1)
					(thickness 0.15)
				)
			)
		)
		(property "Public" ""
			(at 0 0 0)
			(unlocked yes)
			(layer "F.Fab")
			(hide yes)
			(effects
				(font
					(size 1 1)
					(thickness 0.15)
				)
			)
		)
		(sheetname "/HDMI + SD Card/")
		(sheetfile "hdmi-sd-card.kicad_sch")
		(attr smd)
		(fp_rect
			(start -0.925 -0.47)
			(end 0.925 0.47)
			(stroke
				(width 0.05)
				(type default)
			)
			(fill no)
			(layer "F.CrtYd")
		)
		(fp_line
			(start -0.494 -0.25)
			(end 0.504 -0.25)
			(stroke
				(width 0.15)
				(type solid)
			)
			(layer "F.Fab")
		)
		(fp_line
			(start -0.494 0.248)
			(end -0.494 -0.25)
			(stroke
				(width 0.15)
				(type solid)
			)
			(layer "F.Fab")
		)
		(fp_line
			(start 0.504 -0.25)
			(end 0.504 0.248)
			(stroke
				(width 0.15)
				(type solid)
			)
			(layer "F.Fab")
		)
		(fp_line
			(start 0.504 0.248)
			(end -0.494 0.248)
			(stroke
				(width 0.15)
				(type solid)
			)
			(layer "F.Fab")
		)
		(fp_text user "License: Apache-2.0"
			(at -0.939 5.799 0)
			(layer "F.Fab")
			(effects
				(font
					(size 0.7 0.7)
					(thickness 0.15)
				)
				(justify left bottom)
			)
		)
		(fp_text user "${REFERENCE}"
			(at -0.939 4.599 0)
			(layer "F.Fab")
			(effects
				(font
					(size 0.7 0.7)
					(thickness 0.15)
				)
				(justify left bottom)
			)
		)
		(fp_text user "Author: Antmicro"
			(at -0.939 3.399 0)
			(layer "F.Fab")
			(effects
				(font
					(size 0.7 0.7)
					(thickness 0.15)
				)
				(justify left bottom)
			)
		)
		(pad "1" smd roundrect
			(at -0.48 0)
			(size 0.59 0.64)
			(layers "F.Cu" "F.Mask" "F.Paste")
			(roundrect_rratio 0.25)
			(net 810 "/HDMI + SD Card/HDMI_VDD")
			(pintype "passive")
		)
		(pad "2" smd roundrect
			(at 0.48 0)
			(size 0.59 0.64)
			(layers "F.Cu" "F.Mask" "F.Paste")
			(roundrect_rratio 0.25)
			(net 1 "GND")
			(pintype "passive")
		)
	)
	(footprint "antmicro-footprints:R_0402_1005Metric"
		(layer "F.Cu")
		(at 248.169499 132.349 90)
		(descr "Resistor SMD 0402")
		(tags "resistor SMD 0402")
		(property "Reference" "R161"
			(at -1.401 -0.772697 90)
			(layer "F.SilkS")
			(effects
				(font
					(size 0.7 0.7)
					(thickness 0.15)
				)
				(justify left bottom)
			)
		)
		(property "Value" "R_47k_0402"
			(at -1.011843 1.772047 90)
			(layer "F.Fab")
			(effects
				(font
					(size 0.7 0.7)
					(thickness 0.15)
				)
				(justify left bottom)
			)
		)
		(property "Datasheet" "https://www.bourns.com/docs/product-datasheets/cr.pdf"
			(at 0 0 90)
			(layer "F.Fab")
			(hide yes)
			(effects
				(font
					(size 1.27 1.27)
					(thickness 0.15)
				)
			)
		)
		(property "Manufacturer" "Bourns"
			(at 0 0 90)
			(unlocked yes)
			(layer "F.Fab")
			(hide yes)
			(effects
				(font
					(size 1 1)
					(thickness 0.15)
				)
			)
		)
		(property "MPN" "CR0402-FX-4702GLF"
			(at 0 0 90)
			(unlocked yes)
			(layer "F.Fab")
			(hide yes)
			(effects
				(font
					(size 1 1)
					(thickness 0.15)
				)
			)
		)
		(property "Val" "47k"
			(at 0 0 90)
			(unlocked yes)
			(layer "F.Fab")
			(hide yes)
			(effects
				(font
					(size 1 1)
					(thickness 0.15)
				)
			)
		)
		(property "License" "Apache-2.0"
			(at 0 0 90)
			(unlocked yes)
			(layer "F.Fab")
			(hide yes)
			(effects
				(font
					(size 1 1)
					(thickness 0.15)
				)
			)
		)
		(property "Author" "Antmicro"
			(at 0 0 90)
			(unlocked yes)
			(layer "F.Fab")
			(hide yes)
			(effects
				(font
					(size 1 1)
					(thickness 0.15)
				)
			)
		)
		(property "Tolerance" "1%"
			(at 0 0 90)
			(unlocked yes)
			(layer "F.Fab")
			(hide yes)
			(effects
				(font
					(size 1 1)
					(thickness 0.15)
				)
			)
		)
		(sheetname "/Supply/")
		(sheetfile "supply.kicad_sch")
		(attr smd)
		(fp_rect
			(start -0.925 -0.47)
			(end 0.925 0.47)
			(stroke
				(width 0.05)
				(type default)
			)
			(fill no)
			(layer "F.CrtYd")
		)
		(fp_rect
			(start -0.5 -0.25)
			(end 0.5 0.25)
			(stroke
				(width 0.15)
				(type solid)
			)
			(fill no)
			(layer "F.Fab")
		)
		(fp_text user "License: Apache-2.0"
			(at -0.95 5.169 90)
			(layer "F.Fab")
			(effects
				(font
					(size 0.7 0.7)
					(thickness 0.15)
				)
				(justify left bottom)
			)
		)
		(fp_text user "${REFERENCE}"
			(at -0.95 3.168 90)
			(layer "F.Fab")
			(effects
				(font
					(size 0.7 0.7)
					(thickness 0.15)
				)
				(justify left bottom)
			)
		)
		(fp_text user "Author: Antmicro"
			(at -0.95 4.169 90)
			(layer "F.Fab")
			(effects
				(font
					(size 0.7 0.7)
					(thickness 0.15)
				)
				(justify left bottom)
			)
		)
		(pad "1" smd roundrect
			(at -0.48 0 90)
			(size 0.59 0.64)
			(layers "F.Cu" "F.Mask" "F.Paste")
			(roundrect_rratio 0.25)
			(net 1 "GND")
			(pintype "passive")
		)
		(pad "2" smd roundrect
			(at 0.48 0 90)
			(size 0.59 0.64)
			(layers "F.Cu" "F.Mask" "F.Paste")
			(roundrect_rratio 0.25)
			(net 185 "FPGA_POWER_OFF")
			(pintype "passive")
		)
	)
	(footprint "antmicro-footprints:NetTie-2_SMD_Pad0.127mm"
		(layer "F.Cu")
		(at 245.873877 167.95 180)
		(descr "Net tie, 2 pin, 0.127mm  SMD pads")
		(tags "net tie")
		(property "Reference" "NT10"
			(at -0.128 -1.345 0)
			(layer "F.SilkS")
			(hide yes)
			(effects
				(font
					(size 0.7 0.7)
					(thickness 0.15)
				)
				(justify right bottom)
			)
		)
		(property "Value" "Net-Tie_P0.127mm"
			(at 0 1.199 0)
			(layer "F.Fab")
			(effects
				(font
					(size 0.7 0.7)
					(thickness 0.15)
				)
				(justify right bottom)
			)
		)
		(property "MPN" ""
			(at 0 0 180)
			(unlocked yes)
			(layer "F.Fab")
			(hide yes)
			(effects
				(font
					(size 1 1)
					(thickness 0.15)
				)
			)
		)
		(property "Manufacturer" ""
			(at 0 0 180)
			(unlocked yes)
			(layer "F.Fab")
			(hide yes)
			(effects
				(font
					(size 1 1)
					(thickness 0.15)
				)
			)
		)
		(property "Author" "Antmicro"
			(at 0 0 180)
			(unlocked yes)
			(layer "F.Fab")
			(hide yes)
			(effects
				(font
					(size 1 1)
					(thickness 0.15)
				)
			)
		)
		(property "License" "Apache-2.0"
			(at 0 0 180)
			(unlocked yes)
			(layer "F.Fab")
			(hide yes)
			(effects
				(font
					(size 1 1)
					(thickness 0.15)
				)
			)
		)
		(property ki_fp_filters "Net*Tie*")
		(sheetname "/Supply/DC-DC AUX, MGT/")
		(sheetfile "dc-dc-aux-mgt.kicad_sch")
		(attr through_hole exclude_from_pos_files exclude_from_bom)
		(net_tie_pad_groups "1, 2")
		(fp_poly
			(pts
				(xy -0.0635 -0.0635) (xy 0.0625 -0.0635) (xy 0.0625 0.0635) (xy -0.0635 0.0635)
			)
			(stroke
				(width 0)
				(type solid)
			)
			(fill yes)
			(layer "F.Cu")
		)
		(fp_poly
			(pts
				(xy 0.2 -0.16) (xy 0.29 -0.07) (xy 0.29 0.07) (xy 0.2 0.16) (xy -0.2 0.16) (xy -0.29 0.07) (xy -0.29 -0.06)
				(xy -0.19 -0.16)
			)
			(stroke
				(width 0.05)
				(type solid)
			)
			(fill no)
			(layer "F.CrtYd")
		)
		(fp_text user "License: Apache-2.0"
			(at -0.128 5.6 180)
			(layer "F.Fab")
			(effects
				(font
					(size 0.7 0.7)
					(thickness 0.15)
				)
				(justify left bottom)
			)
		)
		(fp_text user "Author: Antmicro"
			(at -0.128 4.4 180)
			(layer "F.Fab")
			(effects
				(font
					(size 0.7 0.7)
					(thickness 0.15)
				)
				(justify left bottom)
			)
		)
		(fp_text user "${REFERENCE}"
			(at -0.128 3.2 180)
			(layer "F.Fab")
			(effects
				(font
					(size 0.7 0.7)
					(thickness 0.15)
				)
				(justify left bottom)
			)
		)
		(pad "1" smd roundrect
			(at -0.127 0)
			(size 0.127 0.127)
			(layers "F.Cu")
			(roundrect_rratio 0.5)
			(chamfer_ratio 0)
			(chamfer top_left bottom_left)
			(net 690 "/Supply/DC-DC AUX, MGT/MGTAVTT_SEN_-")
			(pinfunction "1")
			(pintype "passive")
		)
		(pad "2" smd roundrect
			(at 0.126 0 180)
			(size 0.127 0.127)
			(layers "F.Cu")
			(roundrect_rratio 0.5)
			(chamfer_ratio 0)
			(chamfer top_left bottom_left)
			(net 172 "+1V2_MGTAVTT")
			(pinfunction "2")
			(pintype "passive")
		)
	)
)
